G04*
G04 #@! TF.GenerationSoftware,Altium Limited,Altium Designer,22.4.2 (48)*
G04*
G04 Layer_Color=8421504*
%FSLAX25Y25*%
%MOIN*%
G70*
G04*
G04 #@! TF.SameCoordinates,446674BB-F454-490D-8607-5140536C8ADF*
G04*
G04*
G04 #@! TF.FilePolarity,Positive*
G04*
G01*
G75*
%ADD26R,0.05709X0.07480*%
%ADD27R,0.07087X0.00984*%
%ADD28R,0.04331X0.04134*%
%ADD29R,0.11417X0.21260*%
%ADD30R,0.02244X0.07756*%
%ADD31R,0.02835X0.03937*%
%ADD32R,0.04528X0.05709*%
%ADD33R,0.05709X0.04528*%
%ADD34R,0.03937X0.02835*%
%ADD35R,0.03347X0.03740*%
%ADD36R,0.03937X0.03740*%
%ADD37R,0.12362X0.06063*%
%ADD38R,0.05315X0.06693*%
%ADD39R,0.00984X0.06102*%
%ADD40R,0.06693X0.05315*%
%ADD41R,0.06102X0.00984*%
%ADD42R,0.06650X0.04400*%
%ADD43R,0.05000X0.20000*%
%ADD44R,0.02756X0.03543*%
%ADD45R,0.03740X0.05709*%
%ADD46R,0.05709X0.03740*%
%ADD47R,0.03543X0.01968*%
%ADD48R,0.01968X0.03543*%
%ADD49R,0.03347X0.01181*%
%ADD50R,0.08287X0.04409*%
%ADD51R,0.03150X0.03150*%
%ADD52R,0.03740X0.03150*%
%ADD53R,0.03543X0.01024*%
%ADD54R,0.01024X0.03543*%
%ADD55R,0.12795X0.12795*%
%ADD56R,0.03543X0.02362*%
%ADD57R,0.02165X0.02362*%
%ADD58R,0.03150X0.03543*%
%ADD59R,0.03740X0.03740*%
%ADD60R,0.03543X0.02953*%
%ADD61R,0.08661X0.04134*%
%ADD62R,0.04134X0.03937*%
%ADD63R,0.03740X0.03740*%
%ADD64R,0.04134X0.04331*%
%ADD65R,0.02953X0.03347*%
%ADD66R,0.03937X0.04921*%
%ADD67R,0.04921X0.03937*%
%ADD68R,0.05512X0.05512*%
%ADD69R,0.03937X0.05512*%
%ADD70R,0.02362X0.03150*%
%ADD71R,0.02362X0.02559*%
%ADD72R,0.02800X0.16500*%
%ADD73R,0.02800X0.12600*%
%ADD74O,0.08661X0.02362*%
%ADD75O,0.07480X0.02362*%
%ADD76R,0.02657X0.00984*%
%ADD77R,0.00984X0.02657*%
%ADD78R,0.01968X0.01378*%
G04:AMPARAMS|DCode=79|XSize=40.88mil|YSize=20.95mil|CornerRadius=10.48mil|HoleSize=0mil|Usage=FLASHONLY|Rotation=270.000|XOffset=0mil|YOffset=0mil|HoleType=Round|Shape=RoundedRectangle|*
%AMROUNDEDRECTD79*
21,1,0.04088,0.00000,0,0,270.0*
21,1,0.01993,0.02095,0,0,270.0*
1,1,0.02095,0.00000,-0.00996*
1,1,0.02095,0.00000,0.00996*
1,1,0.02095,0.00000,0.00996*
1,1,0.02095,0.00000,-0.00996*
%
%ADD79ROUNDEDRECTD79*%
%ADD80R,0.02095X0.04088*%
%ADD81R,0.03740X0.03937*%
%ADD82R,0.03937X0.03347*%
%ADD83R,0.03543X0.02756*%
D26*
X335925Y-124803D02*
D03*
X347539D02*
D03*
X359941Y-136221D02*
D03*
X371555D02*
D03*
X653839Y-260236D02*
D03*
X642224D02*
D03*
X359154Y-124803D02*
D03*
X370768D02*
D03*
D27*
X293445Y-245593D02*
D03*
X309193D02*
D03*
X293445Y-243593D02*
D03*
X309193D02*
D03*
X293445Y-241593D02*
D03*
X309193D02*
D03*
X293445Y-239593D02*
D03*
X309193D02*
D03*
X293445Y-237593D02*
D03*
X309193D02*
D03*
X293445Y-235593D02*
D03*
X309193D02*
D03*
X293445Y-233593D02*
D03*
X309193D02*
D03*
X293445Y-231593D02*
D03*
X309193D02*
D03*
X293445Y-229593D02*
D03*
X309193D02*
D03*
Y-227593D02*
D03*
X293445D02*
D03*
Y-245593D02*
D03*
X309193D02*
D03*
X293445Y-243593D02*
D03*
X309193D02*
D03*
X293445Y-241593D02*
D03*
X309193D02*
D03*
X293445Y-239593D02*
D03*
X309193D02*
D03*
X293445Y-237593D02*
D03*
X309193D02*
D03*
X293445Y-235593D02*
D03*
X309193D02*
D03*
X293445Y-233593D02*
D03*
X309193D02*
D03*
X293445Y-231593D02*
D03*
X309193D02*
D03*
X293445Y-229593D02*
D03*
X309193D02*
D03*
Y-227593D02*
D03*
X293445D02*
D03*
D28*
X639764Y-236221D02*
D03*
Y-241732D02*
D03*
X554419Y-216650D02*
D03*
Y-222161D02*
D03*
X602919Y-243661D02*
D03*
Y-238150D02*
D03*
X586419Y-243661D02*
D03*
Y-238150D02*
D03*
X596919Y-243661D02*
D03*
Y-238150D02*
D03*
X591919Y-243661D02*
D03*
Y-238150D02*
D03*
X82677Y-123228D02*
D03*
Y-128740D02*
D03*
X75845Y-116496D02*
D03*
Y-110984D02*
D03*
X500000Y-137647D02*
D03*
Y-132135D02*
D03*
X67913Y-335433D02*
D03*
Y-329921D02*
D03*
X601723Y-136417D02*
D03*
Y-141929D02*
D03*
X581250Y-136417D02*
D03*
Y-141929D02*
D03*
X588337Y-136417D02*
D03*
Y-141929D02*
D03*
X595030Y-136417D02*
D03*
Y-141929D02*
D03*
X544813Y-120161D02*
D03*
Y-114650D02*
D03*
X114173Y-73868D02*
D03*
Y-79379D02*
D03*
X98425Y-92568D02*
D03*
Y-98080D02*
D03*
X348106Y-104238D02*
D03*
Y-98726D02*
D03*
X447835Y-128592D02*
D03*
Y-123080D02*
D03*
X244094Y-115206D02*
D03*
Y-120718D02*
D03*
X67913Y-169488D02*
D03*
Y-175000D02*
D03*
X68898Y-275787D02*
D03*
Y-281299D02*
D03*
X68898Y-221654D02*
D03*
Y-227165D02*
D03*
X528543Y-112057D02*
D03*
Y-117569D02*
D03*
D29*
X600984Y-173622D02*
D03*
X562795D02*
D03*
X579824Y-274905D02*
D03*
X618013D02*
D03*
D30*
X560919Y-243150D02*
D03*
X565919D02*
D03*
X570919D02*
D03*
X575919D02*
D03*
Y-223661D02*
D03*
X570919D02*
D03*
X565919D02*
D03*
X560919D02*
D03*
X551813Y-120661D02*
D03*
X556813D02*
D03*
X561813D02*
D03*
X566813D02*
D03*
Y-140150D02*
D03*
X561813D02*
D03*
X556813D02*
D03*
X551813D02*
D03*
D31*
X549702Y-231906D02*
D03*
X555135D02*
D03*
X570757Y-206890D02*
D03*
X576191D02*
D03*
X571097Y-117206D02*
D03*
X576530D02*
D03*
X654291Y-249606D02*
D03*
X648858D02*
D03*
X618298Y-118307D02*
D03*
X623731D02*
D03*
X540597Y-128405D02*
D03*
X546030D02*
D03*
X561211Y-105315D02*
D03*
X566644D02*
D03*
X110709Y-263632D02*
D03*
X116142D02*
D03*
D32*
X547376Y-240905D02*
D03*
X554462D02*
D03*
X545857Y-138406D02*
D03*
X538770D02*
D03*
X619439Y-132480D02*
D03*
X626526D02*
D03*
X619439Y-141142D02*
D03*
X626526D02*
D03*
D33*
X610919Y-243949D02*
D03*
Y-236862D02*
D03*
X621919Y-243949D02*
D03*
Y-236862D02*
D03*
X648425Y-234252D02*
D03*
Y-241339D02*
D03*
X357480Y-96850D02*
D03*
Y-103937D02*
D03*
D34*
X582135Y-227795D02*
D03*
Y-233228D02*
D03*
X582419Y-217189D02*
D03*
Y-222622D02*
D03*
X573770Y-136063D02*
D03*
Y-141496D02*
D03*
D35*
X570761Y-212906D02*
D03*
X576076D02*
D03*
X566471Y-111406D02*
D03*
X561156D02*
D03*
D36*
X568569Y-254906D02*
D03*
X562269D02*
D03*
D37*
X672835Y-214469D02*
D03*
Y-240650D02*
D03*
Y-289862D02*
D03*
Y-263681D02*
D03*
D38*
X386914Y-160521D02*
D03*
X474906D02*
D03*
Y-308553D02*
D03*
X386914D02*
D03*
D39*
X424024Y-168449D02*
D03*
X422056D02*
D03*
X447647D02*
D03*
X463394D02*
D03*
X451584D02*
D03*
X443710D02*
D03*
X455521D02*
D03*
X433868D02*
D03*
X437805D02*
D03*
X453552Y-152505D02*
D03*
X445679D02*
D03*
X451584D02*
D03*
X463394D02*
D03*
X461427Y-168449D02*
D03*
X457489D02*
D03*
X406309D02*
D03*
X427961D02*
D03*
X447647Y-152505D02*
D03*
X457489D02*
D03*
X453552Y-168449D02*
D03*
X445679D02*
D03*
X441742D02*
D03*
X425993D02*
D03*
X461427Y-152505D02*
D03*
X435836Y-168449D02*
D03*
X431898D02*
D03*
X455521Y-152505D02*
D03*
X416151Y-168449D02*
D03*
X418119D02*
D03*
X412214Y-152505D02*
D03*
X406309D02*
D03*
X441742D02*
D03*
X443710D02*
D03*
X404340Y-168449D02*
D03*
X396465Y-152505D02*
D03*
X394498Y-168449D02*
D03*
X418119Y-152505D02*
D03*
X404340D02*
D03*
X414183D02*
D03*
X416151D02*
D03*
X422056D02*
D03*
X433868D02*
D03*
X427961D02*
D03*
X398434D02*
D03*
X408277D02*
D03*
X402372D02*
D03*
X435836D02*
D03*
X396465Y-168449D02*
D03*
X394498Y-152505D02*
D03*
X424024D02*
D03*
X437805D02*
D03*
X398434Y-168449D02*
D03*
X392529D02*
D03*
X402372D02*
D03*
X392529Y-152505D02*
D03*
X408277Y-168449D02*
D03*
X431898Y-152505D02*
D03*
X425993D02*
D03*
X412214Y-168449D02*
D03*
X465364Y-152505D02*
D03*
Y-168449D02*
D03*
X400403D02*
D03*
X410246D02*
D03*
X420088D02*
D03*
X429931D02*
D03*
X439773D02*
D03*
X449615D02*
D03*
X459457D02*
D03*
X400403Y-152505D02*
D03*
X410246D02*
D03*
X420088D02*
D03*
X429931D02*
D03*
X439773D02*
D03*
X449615D02*
D03*
X459457D02*
D03*
X469301D02*
D03*
Y-168449D02*
D03*
X467332D02*
D03*
X414183D02*
D03*
X467332Y-152505D02*
D03*
X437795Y-300625D02*
D03*
X439763D02*
D03*
X414173D02*
D03*
X398425D02*
D03*
X410236D02*
D03*
X418110D02*
D03*
X406299D02*
D03*
X427952D02*
D03*
X424015D02*
D03*
X408267Y-316569D02*
D03*
X416141D02*
D03*
X410236D02*
D03*
X398425D02*
D03*
X400393Y-300625D02*
D03*
X404330D02*
D03*
X455511D02*
D03*
X433858D02*
D03*
X414173Y-316569D02*
D03*
X404330D02*
D03*
X408267Y-300625D02*
D03*
X416141D02*
D03*
X420078D02*
D03*
X435826D02*
D03*
X400393Y-316569D02*
D03*
X425984Y-300625D02*
D03*
X429921D02*
D03*
X406299Y-316569D02*
D03*
X445669Y-300625D02*
D03*
X443700D02*
D03*
X449606Y-316569D02*
D03*
X455511D02*
D03*
X420078D02*
D03*
X418110D02*
D03*
X457480Y-300625D02*
D03*
X465354Y-316569D02*
D03*
X467322Y-300625D02*
D03*
X443700Y-316569D02*
D03*
X457480D02*
D03*
X447637D02*
D03*
X445669D02*
D03*
X439763D02*
D03*
X427952D02*
D03*
X433858D02*
D03*
X463385D02*
D03*
X453543D02*
D03*
X459448D02*
D03*
X425984D02*
D03*
X465354Y-300625D02*
D03*
X467322Y-316569D02*
D03*
X437795D02*
D03*
X424015D02*
D03*
X463385Y-300625D02*
D03*
X469291D02*
D03*
X459448D02*
D03*
X469291Y-316569D02*
D03*
X453543Y-300625D02*
D03*
X429921Y-316569D02*
D03*
X435826D02*
D03*
X449606Y-300625D02*
D03*
X396456Y-316569D02*
D03*
Y-300625D02*
D03*
X461417D02*
D03*
X451574D02*
D03*
X441732D02*
D03*
X431889D02*
D03*
X422047D02*
D03*
X412204D02*
D03*
X402362D02*
D03*
X461417Y-316569D02*
D03*
X451574D02*
D03*
X441732D02*
D03*
X431889D02*
D03*
X422047D02*
D03*
X412204D02*
D03*
X402362D02*
D03*
X392519D02*
D03*
Y-300625D02*
D03*
X394488D02*
D03*
X447637D02*
D03*
X394488Y-316569D02*
D03*
D40*
X528351Y-190049D02*
D03*
Y-278041D02*
D03*
X340949D02*
D03*
Y-190049D02*
D03*
D41*
X520423Y-227160D02*
D03*
Y-225192D02*
D03*
Y-250782D02*
D03*
Y-266530D02*
D03*
Y-254719D02*
D03*
Y-246845D02*
D03*
Y-258656D02*
D03*
Y-237003D02*
D03*
Y-240940D02*
D03*
X536367Y-256688D02*
D03*
Y-248814D02*
D03*
Y-254719D02*
D03*
Y-266530D02*
D03*
X520423Y-264562D02*
D03*
Y-260625D02*
D03*
Y-209444D02*
D03*
Y-231097D02*
D03*
X536367Y-250782D02*
D03*
Y-260625D02*
D03*
X520423Y-256688D02*
D03*
Y-248814D02*
D03*
Y-244877D02*
D03*
Y-229129D02*
D03*
X536367Y-264562D02*
D03*
X520423Y-238971D02*
D03*
Y-235034D02*
D03*
X536367Y-258656D02*
D03*
X520423Y-219286D02*
D03*
Y-221255D02*
D03*
X536367Y-215349D02*
D03*
Y-209444D02*
D03*
Y-244877D02*
D03*
Y-246845D02*
D03*
X520423Y-207475D02*
D03*
X536367Y-199601D02*
D03*
X520423Y-197633D02*
D03*
X536367Y-221255D02*
D03*
Y-207475D02*
D03*
Y-217318D02*
D03*
Y-219286D02*
D03*
Y-225192D02*
D03*
Y-237003D02*
D03*
Y-231097D02*
D03*
Y-201570D02*
D03*
Y-211412D02*
D03*
Y-205507D02*
D03*
Y-238971D02*
D03*
X520423Y-199601D02*
D03*
X536367Y-197633D02*
D03*
Y-227160D02*
D03*
Y-240940D02*
D03*
X520423Y-201570D02*
D03*
Y-195664D02*
D03*
Y-205507D02*
D03*
X536367Y-195664D02*
D03*
X520423Y-211412D02*
D03*
X536367Y-235034D02*
D03*
Y-229129D02*
D03*
X520423Y-215349D02*
D03*
X536367Y-268499D02*
D03*
X520423D02*
D03*
Y-203538D02*
D03*
Y-213381D02*
D03*
Y-223223D02*
D03*
Y-233066D02*
D03*
Y-242908D02*
D03*
Y-252751D02*
D03*
Y-262593D02*
D03*
X536367Y-203538D02*
D03*
Y-213381D02*
D03*
Y-223223D02*
D03*
Y-233066D02*
D03*
Y-242908D02*
D03*
Y-252751D02*
D03*
Y-262593D02*
D03*
Y-272436D02*
D03*
X520423D02*
D03*
Y-270467D02*
D03*
Y-217318D02*
D03*
X536367Y-270467D02*
D03*
X348876Y-240930D02*
D03*
Y-242898D02*
D03*
Y-217308D02*
D03*
Y-201560D02*
D03*
Y-213371D02*
D03*
Y-221245D02*
D03*
Y-209434D02*
D03*
Y-231087D02*
D03*
Y-227150D02*
D03*
X332932Y-211402D02*
D03*
Y-219276D02*
D03*
Y-213371D02*
D03*
Y-201560D02*
D03*
X348876Y-203528D02*
D03*
Y-207465D02*
D03*
Y-258646D02*
D03*
Y-236993D02*
D03*
X332932Y-217308D02*
D03*
Y-207465D02*
D03*
X348876Y-211402D02*
D03*
Y-219276D02*
D03*
Y-223213D02*
D03*
Y-238961D02*
D03*
X332932Y-203528D02*
D03*
X348876Y-229119D02*
D03*
Y-233056D02*
D03*
X332932Y-209434D02*
D03*
X348876Y-248804D02*
D03*
Y-246835D02*
D03*
X332932Y-252741D02*
D03*
Y-258646D02*
D03*
Y-223213D02*
D03*
Y-221245D02*
D03*
X348876Y-260615D02*
D03*
X332932Y-268489D02*
D03*
X348876Y-270457D02*
D03*
X332932Y-246835D02*
D03*
Y-260615D02*
D03*
Y-250772D02*
D03*
Y-248804D02*
D03*
Y-242898D02*
D03*
Y-231087D02*
D03*
Y-236993D02*
D03*
Y-266520D02*
D03*
Y-256678D02*
D03*
Y-262583D02*
D03*
Y-229119D02*
D03*
X348876Y-268489D02*
D03*
X332932Y-270457D02*
D03*
Y-240930D02*
D03*
Y-227150D02*
D03*
X348876Y-266520D02*
D03*
Y-272426D02*
D03*
Y-262583D02*
D03*
X332932Y-272426D02*
D03*
X348876Y-256678D02*
D03*
X332932Y-233056D02*
D03*
Y-238961D02*
D03*
X348876Y-252741D02*
D03*
X332932Y-199591D02*
D03*
X348876D02*
D03*
Y-264552D02*
D03*
Y-254709D02*
D03*
Y-244867D02*
D03*
Y-235024D02*
D03*
Y-225182D02*
D03*
Y-215339D02*
D03*
Y-205497D02*
D03*
X332932Y-264552D02*
D03*
Y-254709D02*
D03*
Y-244867D02*
D03*
Y-235024D02*
D03*
Y-225182D02*
D03*
Y-215339D02*
D03*
Y-205497D02*
D03*
Y-195654D02*
D03*
X348876D02*
D03*
Y-197623D02*
D03*
Y-250772D02*
D03*
X332932Y-197623D02*
D03*
D42*
X630240Y-37647D02*
D03*
X649390D02*
D03*
Y-29773D02*
D03*
X630240D02*
D03*
Y-21899D02*
D03*
X649390D02*
D03*
X630240Y-14025D02*
D03*
X649390D02*
D03*
X74036Y-73671D02*
D03*
X93186D02*
D03*
X74036Y-65797D02*
D03*
X93186D02*
D03*
Y-57923D02*
D03*
X74036D02*
D03*
Y-50049D02*
D03*
X93186D02*
D03*
D43*
X609291Y-316535D02*
D03*
Y-343543D02*
D03*
X599291Y-316535D02*
D03*
Y-343543D02*
D03*
X589291Y-316535D02*
D03*
Y-343543D02*
D03*
X579291Y-316535D02*
D03*
Y-343543D02*
D03*
X569291Y-316535D02*
D03*
Y-343543D02*
D03*
D44*
X262806Y-132277D02*
D03*
X257294D02*
D03*
X248031Y-127165D02*
D03*
X242520D02*
D03*
X59646Y-316929D02*
D03*
X54134D02*
D03*
X60827Y-210630D02*
D03*
X55315D02*
D03*
X60827Y-262795D02*
D03*
X55315D02*
D03*
X54331Y-157480D02*
D03*
X59842D02*
D03*
D45*
X540493Y-331738D02*
D03*
X532619D02*
D03*
X540099Y-347880D02*
D03*
X532225D02*
D03*
D46*
X655118Y-346457D02*
D03*
Y-338583D02*
D03*
X637008Y-346850D02*
D03*
Y-338976D02*
D03*
D47*
X515198Y-329179D02*
D03*
Y-334297D02*
D03*
X524056Y-331738D02*
D03*
X515099Y-345321D02*
D03*
Y-350439D02*
D03*
X523958Y-347880D02*
D03*
D48*
X639567Y-320374D02*
D03*
X634449D02*
D03*
X637008Y-329232D02*
D03*
X658268Y-320473D02*
D03*
X653150D02*
D03*
X655709Y-329331D02*
D03*
D49*
X81988Y-215551D02*
D03*
Y-213583D02*
D03*
Y-211614D02*
D03*
Y-209646D02*
D03*
X69587D02*
D03*
Y-211614D02*
D03*
Y-213583D02*
D03*
Y-215551D02*
D03*
X81004Y-162402D02*
D03*
Y-160433D02*
D03*
Y-158465D02*
D03*
Y-156496D02*
D03*
X68602D02*
D03*
Y-158465D02*
D03*
Y-160433D02*
D03*
Y-162402D02*
D03*
X81988Y-267717D02*
D03*
Y-265748D02*
D03*
Y-263779D02*
D03*
Y-261811D02*
D03*
X69587D02*
D03*
Y-263779D02*
D03*
Y-265748D02*
D03*
Y-267717D02*
D03*
X81004Y-321850D02*
D03*
Y-319882D02*
D03*
Y-317913D02*
D03*
Y-315945D02*
D03*
X68602D02*
D03*
Y-317913D02*
D03*
Y-319882D02*
D03*
Y-321850D02*
D03*
D50*
X649390Y-14025D02*
D03*
Y-29773D02*
D03*
Y-21899D02*
D03*
Y-37647D02*
D03*
X631890Y-14025D02*
D03*
Y-21899D02*
D03*
Y-29773D02*
D03*
Y-37647D02*
D03*
X74036Y-73671D02*
D03*
Y-57923D02*
D03*
Y-65797D02*
D03*
Y-50049D02*
D03*
X91536Y-73671D02*
D03*
Y-65797D02*
D03*
Y-57923D02*
D03*
Y-50049D02*
D03*
D51*
X40354Y14764D02*
D03*
Y8858D02*
D03*
X33465Y14764D02*
D03*
Y8858D02*
D03*
X26575Y14764D02*
D03*
Y8858D02*
D03*
X47244Y14764D02*
D03*
Y8858D02*
D03*
D52*
Y-4626D02*
D03*
Y689D02*
D03*
X40354Y-4626D02*
D03*
Y689D02*
D03*
X33465Y-4626D02*
D03*
Y689D02*
D03*
X26575Y-4626D02*
D03*
Y689D02*
D03*
X199803Y-119439D02*
D03*
Y-114517D02*
D03*
D53*
X94193Y-120079D02*
D03*
Y-122047D02*
D03*
Y-124016D02*
D03*
Y-125984D02*
D03*
Y-127953D02*
D03*
Y-129921D02*
D03*
Y-131890D02*
D03*
X112500D02*
D03*
Y-129921D02*
D03*
Y-127953D02*
D03*
Y-125984D02*
D03*
Y-124016D02*
D03*
Y-122047D02*
D03*
Y-120079D02*
D03*
D54*
X97441Y-135138D02*
D03*
X99410D02*
D03*
X101378D02*
D03*
X103347D02*
D03*
X105315D02*
D03*
X107283D02*
D03*
X109252D02*
D03*
X109252Y-116831D02*
D03*
X107283D02*
D03*
X105315D02*
D03*
X103347D02*
D03*
X101378D02*
D03*
X99410D02*
D03*
X97441D02*
D03*
D55*
X103347Y-125984D02*
D03*
D56*
X-18406Y-187795D02*
D03*
Y-176772D02*
D03*
Y-240551D02*
D03*
Y-229528D02*
D03*
Y-294094D02*
D03*
Y-283071D02*
D03*
Y-346850D02*
D03*
Y-335827D02*
D03*
Y-113976D02*
D03*
Y-102953D02*
D03*
Y-70669D02*
D03*
Y-59646D02*
D03*
D57*
X-19685Y-184055D02*
D03*
Y-180512D02*
D03*
Y-236811D02*
D03*
Y-233268D02*
D03*
Y-290354D02*
D03*
Y-286811D02*
D03*
Y-343110D02*
D03*
Y-339567D02*
D03*
Y-110236D02*
D03*
Y-106693D02*
D03*
Y-66929D02*
D03*
Y-63386D02*
D03*
D58*
X82677Y-116535D02*
D03*
Y-109843D02*
D03*
D59*
X82677Y-135827D02*
D03*
X76772D02*
D03*
D60*
X75787Y-127756D02*
D03*
Y-123031D02*
D03*
D61*
X44291Y-256988D02*
D03*
Y-268602D02*
D03*
Y-151673D02*
D03*
Y-163287D02*
D03*
Y-311122D02*
D03*
Y-322736D02*
D03*
Y-204823D02*
D03*
Y-216437D02*
D03*
D62*
X38287Y-262795D02*
D03*
Y-157480D02*
D03*
Y-316929D02*
D03*
Y-210630D02*
D03*
D63*
X74803Y-335630D02*
D03*
Y-329724D02*
D03*
X82677Y-335630D02*
D03*
Y-329724D02*
D03*
X75787Y-227362D02*
D03*
Y-221457D02*
D03*
X82677Y-227362D02*
D03*
Y-221457D02*
D03*
X83661Y-281496D02*
D03*
Y-275590D02*
D03*
X75787Y-281496D02*
D03*
Y-275590D02*
D03*
X74803Y-175197D02*
D03*
Y-169291D02*
D03*
X82677Y-175197D02*
D03*
Y-169291D02*
D03*
X399606Y-134695D02*
D03*
Y-128789D02*
D03*
X405512Y-134695D02*
D03*
Y-128789D02*
D03*
D64*
X487205Y-137647D02*
D03*
X481693D02*
D03*
X650197Y-50049D02*
D03*
X644685D02*
D03*
X615522Y-14017D02*
D03*
X610010D02*
D03*
X263976Y-112057D02*
D03*
X269488D02*
D03*
X518701D02*
D03*
X513189D02*
D03*
D65*
X460925Y-137647D02*
D03*
X456398D02*
D03*
D66*
X643701Y-58907D02*
D03*
X651575D02*
D03*
X609252Y-21506D02*
D03*
X617126D02*
D03*
D67*
X89567Y-98277D02*
D03*
Y-90403D02*
D03*
X123031Y-79970D02*
D03*
Y-72096D02*
D03*
D68*
X31496Y-184055D02*
D03*
Y-291732D02*
D03*
D69*
X38189Y-184055D02*
D03*
Y-175394D02*
D03*
X30709D02*
D03*
X38189Y-291732D02*
D03*
Y-283071D02*
D03*
X30709D02*
D03*
D70*
X267323Y-126821D02*
D03*
X262205D02*
D03*
X267323Y-118947D02*
D03*
X262205D02*
D03*
D71*
X276969Y-357824D02*
D03*
Y-354478D02*
D03*
X221850Y-357824D02*
D03*
Y-354478D02*
D03*
D72*
X281102Y-401427D02*
D03*
X159055D02*
D03*
X155118D02*
D03*
X151181D02*
D03*
X178740D02*
D03*
X222047D02*
D03*
X265354D02*
D03*
X261417D02*
D03*
X249606D02*
D03*
X245669D02*
D03*
X233858D02*
D03*
X229921D02*
D03*
X214173D02*
D03*
X210236D02*
D03*
X186614D02*
D03*
X182677D02*
D03*
X202362D02*
D03*
X273228D02*
D03*
X166929D02*
D03*
X170866D02*
D03*
X190551D02*
D03*
X269291D02*
D03*
X257480D02*
D03*
X241732D02*
D03*
X237795D02*
D03*
X174803D02*
D03*
X162992D02*
D03*
X253543D02*
D03*
X206299D02*
D03*
X218110D02*
D03*
X225984D02*
D03*
D73*
X277165Y-399477D02*
D03*
D74*
X279528Y-113946D02*
D03*
Y-118947D02*
D03*
Y-123946D02*
D03*
Y-128946D02*
D03*
X298425Y-113946D02*
D03*
Y-118947D02*
D03*
Y-123946D02*
D03*
Y-128946D02*
D03*
D75*
X209252Y-114399D02*
D03*
Y-119399D02*
D03*
Y-124399D02*
D03*
Y-129399D02*
D03*
X227756Y-114399D02*
D03*
Y-119399D02*
D03*
Y-124399D02*
D03*
Y-129399D02*
D03*
D76*
X481250Y-121899D02*
D03*
Y-123868D02*
D03*
Y-125836D02*
D03*
Y-127805D02*
D03*
X491191D02*
D03*
Y-125836D02*
D03*
Y-123868D02*
D03*
Y-121899D02*
D03*
D77*
X484252Y-128838D02*
D03*
X486221D02*
D03*
X488189D02*
D03*
Y-120866D02*
D03*
X486221D02*
D03*
X484252D02*
D03*
D78*
X519783Y-126131D02*
D03*
Y-128691D02*
D03*
X511713D02*
D03*
Y-126131D02*
D03*
Y-123572D02*
D03*
Y-121013D02*
D03*
X519783D02*
D03*
Y-123572D02*
D03*
D79*
X464370Y-130034D02*
D03*
X456890D02*
D03*
Y-121639D02*
D03*
X460630D02*
D03*
D80*
X464370D02*
D03*
D81*
X548425Y-157087D02*
D03*
Y-150787D02*
D03*
D82*
X618012Y-124409D02*
D03*
X623721D02*
D03*
D83*
X237205Y-125639D02*
D03*
Y-120127D02*
D03*
M02*
